(kicad_pcb
	(version 20260206)
	(generator "pcbnew")
	(generator_version "10.0")
	(general
		(thickness 1.6)
		(legacy_teardrops no)
	)
	(paper "A4")
	(title_block
		(title "03242023_DA0F0TMBIJ0_F0T_Motherboard_J_brd_V01_OCP.brd")
		(comment 1 "Grand Teton / footprints 4206-4211 of 6105")
	)
	(layers
		(0 "F.Cu" signal "TOP")
		(4 "In1.Cu" signal "GND")
		(6 "In2.Cu" signal "IN1")
		(8 "In3.Cu" signal "GND1")
		(10 "In4.Cu" signal "IN2")
		(12 "In5.Cu" signal "GND2")
		(14 "In6.Cu" signal "IN3")
		(16 "In7.Cu" signal "GND3")
		(18 "In8.Cu" signal "VCC")
		(20 "In9.Cu" signal "VCC1")
		(22 "In10.Cu" signal "GND4")
		(24 "In11.Cu" signal "IN4")
		(26 "In12.Cu" signal "GND5")
		(28 "In13.Cu" signal "IN5")
		(30 "In14.Cu" signal "GND6")
		(32 "In15.Cu" signal "IN6")
		(34 "In16.Cu" signal "GND7")
		(2 "B.Cu" signal "BOTTOM")
		(9 "F.Adhes" user "F.Adhesive")
		(11 "B.Adhes" user "B.Adhesive")
		(13 "F.Paste" user "Package Geometry/Pastemask Top")
		(15 "B.Paste" user "Package Geometry/Pastemask Bottom")
		(5 "F.SilkS" user "Ref Des/Silkscreen Top")
		(7 "B.SilkS" user "Ref Des/Silkscreen Bottom")
		(1 "F.Mask" user "Board Geometry/Soldermask Top")
		(3 "B.Mask" user "Board Geometry/Soldermask Bottom")
		(17 "Dwgs.User" user "User.Drawings")
		(19 "Cmts.User" user "User.Comments")
		(21 "Eco1.User" user "User.Eco1")
		(23 "Eco2.User" user "User.Eco2")
		(25 "Edge.Cuts" user "Board Geometry/Outline")
		(27 "Margin" user)
		(31 "F.CrtYd" user "Package Geometry/Place Bound Top")
		(29 "B.CrtYd" user "Package Geometry/Place Bound Bottom")
		(35 "F.Fab" user "Ref Des/Assembly Top")
		(33 "B.Fab" user "Ref Des/Assembly Bottom")
	)
	(footprint ""
		(layer "B.Cu")
		(at 274.83562 -318.986408 90)
		(property "Reference" "R2729"
			(at 0 0 90)
			(layer "B.SilkS")
			(hide yes)
			(effects
				(font
					(size 1.27 1.27)
				)
				(justify mirror)
			)
		)
		(property "Value" ""
			(at 0 0 90)
			(layer "B.Fab")
			(effects
				(font
					(size 1.27 1.27)
				)
				(justify mirror)
			)
		)
		(duplicate_pad_numbers_are_jumpers no)
		(fp_line
			(start 0.7874 -0.4064)
			(end -0.7874 -0.4064)
			(stroke
				(width 0.1524)
				(type default)
			)
			(layer "B.SilkS")
		)
		(fp_line
			(start -0.7874 -0.4064)
			(end -0.7874 0.4064)
			(stroke
				(width 0.1524)
				(type default)
			)
			(layer "B.SilkS")
		)
		(fp_line
			(start 0.7874 0.4064)
			(end 0.7874 -0.4064)
			(stroke
				(width 0.1524)
				(type default)
			)
			(layer "B.SilkS")
		)
		(fp_line
			(start -0.7874 0.4064)
			(end 0.7874 0.4064)
			(stroke
				(width 0.1524)
				(type default)
			)
			(layer "B.SilkS")
		)
		(fp_line
			(start 0.67945 -0.305054)
			(end 0.12065 -0.305054)
			(stroke
				(width 0.1)
				(type default)
			)
			(layer "B.Fab")
		)
		(fp_line
			(start 0.12065 -0.305054)
			(end 0.12065 -0.2794)
			(stroke
				(width 0.1)
				(type default)
			)
			(layer "B.Fab")
		)
		(fp_line
			(start -0.12065 -0.3048)
			(end -0.67945 -0.3048)
			(stroke
				(width 0.1)
				(type default)
			)
			(layer "B.Fab")
		)
		(fp_line
			(start -0.67945 -0.3048)
			(end -0.67945 0.3048)
			(stroke
				(width 0.1)
				(type default)
			)
			(layer "B.Fab")
		)
		(fp_line
			(start 0.12065 -0.2794)
			(end -0.12065 -0.2794)
			(stroke
				(width 0.1)
				(type default)
			)
			(layer "B.Fab")
		)
		(fp_line
			(start -0.12065 -0.2794)
			(end -0.12065 -0.3048)
			(stroke
				(width 0.1)
				(type default)
			)
			(layer "B.Fab")
		)
		(fp_line
			(start 0.12065 0.2794)
			(end 0.12065 0.3048)
			(stroke
				(width 0.1)
				(type default)
			)
			(layer "B.Fab")
		)
		(fp_line
			(start -0.120396 0.2794)
			(end 0.12065 0.2794)
			(stroke
				(width 0.1)
				(type default)
			)
			(layer "B.Fab")
		)
		(fp_line
			(start 0.67945 0.3048)
			(end 0.67945 -0.305054)
			(stroke
				(width 0.1)
				(type default)
			)
			(layer "B.Fab")
		)
		(fp_line
			(start 0.12065 0.3048)
			(end 0.67945 0.3048)
			(stroke
				(width 0.1)
				(type default)
			)
			(layer "B.Fab")
		)
		(fp_line
			(start -0.120396 0.3048)
			(end -0.120396 0.2794)
			(stroke
				(width 0.1)
				(type default)
			)
			(layer "B.Fab")
		)
		(fp_line
			(start -0.67945 0.3048)
			(end -0.120396 0.3048)
			(stroke
				(width 0.1)
				(type default)
			)
			(layer "B.Fab")
		)
		(pad "1" smd circle
			(at 0.40005 0 270)
			(size 0 0)
			(layers "B.Cu" "B.Mask" "B.Paste")
			(net "PWRGD_CHC_CPU0_DIMM1")
		)
		(pad "2" smd circle
			(at -0.40005 0 270)
			(size 0 0)
			(layers "B.Cu" "B.Mask" "B.Paste")
			(net "PWRGD_FAIL_CPU0_CD")
		)
	)
	(footprint ""
		(layer "B.Cu")
		(at 260.121146 -76.558902 -90)
		(property "Reference" "PC2286"
			(at 0 0 90)
			(layer "B.SilkS")
			(hide yes)
			(effects
				(font
					(size 1.27 1.27)
				)
				(justify mirror)
			)
		)
		(property "Value" ""
			(at 0 0 90)
			(layer "B.Fab")
			(effects
				(font
					(size 1.27 1.27)
				)
				(justify mirror)
			)
		)
		(duplicate_pad_numbers_are_jumpers no)
		(fp_line
			(start -0.7874 0.4064)
			(end 0.7874 0.4064)
			(stroke
				(width 0.1524)
				(type default)
			)
			(layer "B.SilkS")
		)
		(fp_line
			(start 0.7874 0.4064)
			(end 0.7874 -0.4064)
			(stroke
				(width 0.1524)
				(type default)
			)
			(layer "B.SilkS")
		)
		(fp_line
			(start -0.7874 -0.4064)
			(end -0.7874 0.4064)
			(stroke
				(width 0.1524)
				(type default)
			)
			(layer "B.SilkS")
		)
		(fp_line
			(start 0.7874 -0.4064)
			(end -0.7874 -0.4064)
			(stroke
				(width 0.1524)
				(type default)
			)
			(layer "B.SilkS")
		)
		(fp_line
			(start -0.67945 0.3048)
			(end -0.120396 0.3048)
			(stroke
				(width 0.1)
				(type default)
			)
			(layer "B.Fab")
		)
		(fp_line
			(start -0.120396 0.3048)
			(end -0.120396 0.2794)
			(stroke
				(width 0.1)
				(type default)
			)
			(layer "B.Fab")
		)
		(fp_line
			(start 0.12065 0.3048)
			(end 0.67945 0.3048)
			(stroke
				(width 0.1)
				(type default)
			)
			(layer "B.Fab")
		)
		(fp_line
			(start 0.67945 0.3048)
			(end 0.67945 -0.305054)
			(stroke
				(width 0.1)
				(type default)
			)
			(layer "B.Fab")
		)
		(fp_line
			(start -0.120396 0.2794)
			(end 0.12065 0.2794)
			(stroke
				(width 0.1)
				(type default)
			)
			(layer "B.Fab")
		)
		(fp_line
			(start 0.12065 0.2794)
			(end 0.12065 0.3048)
			(stroke
				(width 0.1)
				(type default)
			)
			(layer "B.Fab")
		)
		(fp_line
			(start -0.12065 -0.2794)
			(end -0.12065 -0.3048)
			(stroke
				(width 0.1)
				(type default)
			)
			(layer "B.Fab")
		)
		(fp_line
			(start 0.12065 -0.2794)
			(end -0.12065 -0.2794)
			(stroke
				(width 0.1)
				(type default)
			)
			(layer "B.Fab")
		)
		(fp_line
			(start -0.67945 -0.3048)
			(end -0.67945 0.3048)
			(stroke
				(width 0.1)
				(type default)
			)
			(layer "B.Fab")
		)
		(fp_line
			(start -0.12065 -0.3048)
			(end -0.67945 -0.3048)
			(stroke
				(width 0.1)
				(type default)
			)
			(layer "B.Fab")
		)
		(fp_line
			(start 0.12065 -0.305054)
			(end 0.12065 -0.2794)
			(stroke
				(width 0.1)
				(type default)
			)
			(layer "B.Fab")
		)
		(fp_line
			(start 0.67945 -0.305054)
			(end 0.12065 -0.305054)
			(stroke
				(width 0.1)
				(type default)
			)
			(layer "B.Fab")
		)
		(pad "1" smd circle
			(at 0.40005 0 90)
			(size 0 0)
			(layers "B.Cu" "B.Mask" "B.Paste")
			(net "FM_P1V05_PCH_AUX_R_EN")
		)
		(pad "2" smd circle
			(at -0.40005 0 90)
			(size 0 0)
			(layers "B.Cu" "B.Mask" "B.Paste")
			(net "GND")
		)
	)
	(footprint ""
		(layer "B.Cu")
		(at 26.359866 -193.152776 -90)
		(property "Reference" "R817"
			(at 0 0 90)
			(layer "B.SilkS")
			(hide yes)
			(effects
				(font
					(size 1.27 1.27)
				)
				(justify mirror)
			)
		)
		(property "Value" ""
			(at 0 0 90)
			(layer "B.Fab")
			(effects
				(font
					(size 1.27 1.27)
				)
				(justify mirror)
			)
		)
		(duplicate_pad_numbers_are_jumpers no)
		(fp_line
			(start -0.7874 0.4064)
			(end 0.7874 0.4064)
			(stroke
				(width 0.1524)
				(type default)
			)
			(layer "B.SilkS")
		)
		(fp_line
			(start 0.7874 0.4064)
			(end 0.7874 -0.4064)
			(stroke
				(width 0.1524)
				(type default)
			)
			(layer "B.SilkS")
		)
		(fp_line
			(start -0.7874 -0.4064)
			(end -0.7874 0.4064)
			(stroke
				(width 0.1524)
				(type default)
			)
			(layer "B.SilkS")
		)
		(fp_line
			(start 0.7874 -0.4064)
			(end -0.7874 -0.4064)
			(stroke
				(width 0.1524)
				(type default)
			)
			(layer "B.SilkS")
		)
		(fp_line
			(start -0.67945 0.3048)
			(end -0.120396 0.3048)
			(stroke
				(width 0.1)
				(type default)
			)
			(layer "B.Fab")
		)
		(fp_line
			(start -0.120396 0.3048)
			(end -0.120396 0.2794)
			(stroke
				(width 0.1)
				(type default)
			)
			(layer "B.Fab")
		)
		(fp_line
			(start 0.12065 0.3048)
			(end 0.67945 0.3048)
			(stroke
				(width 0.1)
				(type default)
			)
			(layer "B.Fab")
		)
		(fp_line
			(start 0.67945 0.3048)
			(end 0.67945 -0.305054)
			(stroke
				(width 0.1)
				(type default)
			)
			(layer "B.Fab")
		)
		(fp_line
			(start -0.120396 0.2794)
			(end 0.12065 0.2794)
			(stroke
				(width 0.1)
				(type default)
			)
			(layer "B.Fab")
		)
		(fp_line
			(start 0.12065 0.2794)
			(end 0.12065 0.3048)
			(stroke
				(width 0.1)
				(type default)
			)
			(layer "B.Fab")
		)
		(fp_line
			(start -0.12065 -0.2794)
			(end -0.12065 -0.3048)
			(stroke
				(width 0.1)
				(type default)
			)
			(layer "B.Fab")
		)
		(fp_line
			(start 0.12065 -0.2794)
			(end -0.12065 -0.2794)
			(stroke
				(width 0.1)
				(type default)
			)
			(layer "B.Fab")
		)
		(fp_line
			(start -0.67945 -0.3048)
			(end -0.67945 0.3048)
			(stroke
				(width 0.1)
				(type default)
			)
			(layer "B.Fab")
		)
		(fp_line
			(start -0.12065 -0.3048)
			(end -0.67945 -0.3048)
			(stroke
				(width 0.1)
				(type default)
			)
			(layer "B.Fab")
		)
		(fp_line
			(start 0.12065 -0.305054)
			(end 0.12065 -0.2794)
			(stroke
				(width 0.1)
				(type default)
			)
			(layer "B.Fab")
		)
		(fp_line
			(start 0.67945 -0.305054)
			(end 0.12065 -0.305054)
			(stroke
				(width 0.1)
				(type default)
			)
			(layer "B.Fab")
		)
		(pad "1" smd circle
			(at 0.40005 0 90)
			(size 0 0)
			(layers "B.Cu" "B.Mask" "B.Paste")
			(net "RST_PLD_CPU1_DRAM_CD_N")
		)
		(pad "2" smd circle
			(at -0.40005 0 90)
			(size 0 0)
			(layers "B.Cu" "B.Mask" "B.Paste")
			(net "RST_M_CD_CPU1_FPGA_N")
		)
	)
	(footprint ""
		(layer "B.Cu")
		(at 355.397308 -248.498106 -90)
		(property "Reference" "C389"
			(at 0 0 90)
			(layer "B.SilkS")
			(hide yes)
			(effects
				(font
					(size 1.27 1.27)
				)
				(justify mirror)
			)
		)
		(property "Value" ""
			(at 0 0 90)
			(layer "B.Fab")
			(effects
				(font
					(size 1.27 1.27)
				)
				(justify mirror)
			)
		)
		(duplicate_pad_numbers_are_jumpers no)
		(fp_line
			(start -1.524 0.762)
			(end 1.524 0.762)
			(stroke
				(width 0.1524)
				(type default)
			)
			(layer "B.SilkS")
		)
		(fp_line
			(start 1.524 0.762)
			(end 1.524 -0.762)
			(stroke
				(width 0.1524)
				(type default)
			)
			(layer "B.SilkS")
		)
		(fp_line
			(start -1.524 -0.762)
			(end -1.524 0.762)
			(stroke
				(width 0.1524)
				(type default)
			)
			(layer "B.SilkS")
		)
		(fp_line
			(start 1.524 -0.762)
			(end -1.524 -0.762)
			(stroke
				(width 0.1524)
				(type default)
			)
			(layer "B.SilkS")
		)
		(fp_line
			(start -1.1049 0.724916)
			(end -1.1049 -0.724916)
			(stroke
				(width 0.1)
				(type default)
			)
			(layer "B.Fab")
		)
		(fp_line
			(start 1.1049 0.724916)
			(end -1.1049 0.724916)
			(stroke
				(width 0.1)
				(type default)
			)
			(layer "B.Fab")
		)
		(fp_line
			(start -1.1049 -0.724916)
			(end 1.1049 -0.724916)
			(stroke
				(width 0.1)
				(type default)
			)
			(layer "B.Fab")
		)
		(fp_line
			(start 1.1049 -0.724916)
			(end 1.1049 0.724916)
			(stroke
				(width 0.1)
				(type default)
			)
			(layer "B.Fab")
		)
		(pad "1" smd rect
			(at 0.889 0 270)
			(size 1.016 1.27)
			(layers "B.Cu" "B.Mask" "B.Paste")
			(net "PVCCIN_CPU0")
		)
		(pad "2" smd rect
			(at -0.889 0 270)
			(size 1.016 1.27)
			(layers "B.Cu" "B.Mask" "B.Paste")
			(net "GND")
		)
	)
	(footprint ""
		(layer "B.Cu")
		(at 433.297584 -179.818538 90)
		(property "Reference" "C1296"
			(at 0 0 90)
			(layer "B.SilkS")
			(hide yes)
			(effects
				(font
					(size 1.27 1.27)
				)
				(justify mirror)
			)
		)
		(property "Value" ""
			(at 0 0 90)
			(layer "B.Fab")
			(effects
				(font
					(size 1.27 1.27)
				)
				(justify mirror)
			)
		)
		(duplicate_pad_numbers_are_jumpers no)
		(fp_line
			(start 0.7874 -0.4064)
			(end -0.7874 -0.4064)
			(stroke
				(width 0.1524)
				(type default)
			)
			(layer "B.SilkS")
		)
		(fp_line
			(start -0.7874 -0.4064)
			(end -0.7874 0.4064)
			(stroke
				(width 0.1524)
				(type default)
			)
			(layer "B.SilkS")
		)
		(fp_line
			(start 0.7874 0.4064)
			(end 0.7874 -0.4064)
			(stroke
				(width 0.1524)
				(type default)
			)
			(layer "B.SilkS")
		)
		(fp_line
			(start -0.7874 0.4064)
			(end 0.7874 0.4064)
			(stroke
				(width 0.1524)
				(type default)
			)
			(layer "B.SilkS")
		)
		(fp_line
			(start 0.67945 -0.305054)
			(end 0.12065 -0.305054)
			(stroke
				(width 0.1)
				(type default)
			)
			(layer "B.Fab")
		)
		(fp_line
			(start 0.12065 -0.305054)
			(end 0.12065 -0.2794)
			(stroke
				(width 0.1)
				(type default)
			)
			(layer "B.Fab")
		)
		(fp_line
			(start -0.12065 -0.3048)
			(end -0.67945 -0.3048)
			(stroke
				(width 0.1)
				(type default)
			)
			(layer "B.Fab")
		)
		(fp_line
			(start -0.67945 -0.3048)
			(end -0.67945 0.3048)
			(stroke
				(width 0.1)
				(type default)
			)
			(layer "B.Fab")
		)
		(fp_line
			(start 0.12065 -0.2794)
			(end -0.12065 -0.2794)
			(stroke
				(width 0.1)
				(type default)
			)
			(layer "B.Fab")
		)
		(fp_line
			(start -0.12065 -0.2794)
			(end -0.12065 -0.3048)
			(stroke
				(width 0.1)
				(type default)
			)
			(layer "B.Fab")
		)
		(fp_line
			(start 0.12065 0.2794)
			(end 0.12065 0.3048)
			(stroke
				(width 0.1)
				(type default)
			)
			(layer "B.Fab")
		)
		(fp_line
			(start -0.120396 0.2794)
			(end 0.12065 0.2794)
			(stroke
				(width 0.1)
				(type default)
			)
			(layer "B.Fab")
		)
		(fp_line
			(start 0.67945 0.3048)
			(end 0.67945 -0.305054)
			(stroke
				(width 0.1)
				(type default)
			)
			(layer "B.Fab")
		)
		(fp_line
			(start 0.12065 0.3048)
			(end 0.67945 0.3048)
			(stroke
				(width 0.1)
				(type default)
			)
			(layer "B.Fab")
		)
		(fp_line
			(start -0.120396 0.3048)
			(end -0.120396 0.2794)
			(stroke
				(width 0.1)
				(type default)
			)
			(layer "B.Fab")
		)
		(fp_line
			(start -0.67945 0.3048)
			(end -0.120396 0.3048)
			(stroke
				(width 0.1)
				(type default)
			)
			(layer "B.Fab")
		)
		(pad "1" smd circle
			(at 0.40005 0 270)
			(size 0 0)
			(layers "B.Cu" "B.Mask" "B.Paste")
			(net "PWRGD_PVNN_MAIN_CPU0")
		)
		(pad "2" smd circle
			(at -0.40005 0 270)
			(size 0 0)
			(layers "B.Cu" "B.Mask" "B.Paste")
			(net "GND")
		)
	)
	(footprint ""
		(layer "B.Cu")
		(at 477.95688 -251.022866)
		(property "Reference" "DB12"
			(at 2.467356 -5.911342 270)
			(unlocked yes)
			(layer "B.SilkS")
			(effects
				(font
					(size 0.7874 0.5842)
					(thickness 0.1524)
				)
				(justify left mirror)
			)
		)
		(property "Value" ""
			(at 0 0 0)
			(layer "B.Fab")
			(effects
				(font
					(size 1.27 1.27)
				)
				(justify mirror)
			)
		)
		(duplicate_pad_numbers_are_jumpers no)
		(fp_line
			(start -3.330702 -4.771136)
			(end 0 4.011168)
			(stroke
				(width 0.1524)
				(type default)
			)
			(layer "B.SilkS")
		)
		(fp_line
			(start 0 4.011168)
			(end 3.330702 -4.771136)
			(stroke
				(width 0.1524)
				(type default)
			)
			(layer "B.SilkS")
		)
		(fp_line
			(start 3.330702 -4.771136)
			(end -3.330702 -4.771136)
			(stroke
				(width 0.1524)
				(type default)
			)
			(layer "B.SilkS")
		)
		(fp_line
			(start -3.330702 -4.771136)
			(end 0 4.011168)
			(stroke
				(width 0.1)
				(type default)
			)
			(layer "B.Fab")
		)
		(fp_line
			(start 0 4.011168)
			(end 3.330702 -4.771136)
			(stroke
				(width 0.1)
				(type default)
			)
			(layer "B.Fab")
		)
		(fp_line
			(start 3.330702 -4.771136)
			(end -3.330702 -4.771136)
			(stroke
				(width 0.1)
				(type default)
			)
			(layer "B.Fab")
		)
		(pad "1" thru_hole circle
			(at 0 0 180)
			(size 2.159 2.159)
			(drill 1.7018)
			(layers "*.Cu" "*.Mask")
			(remove_unused_layers no)
			(net "T1_GND")
			(clearance 0.0254)
			(thermal_gap 0.0254)
		)
		(pad "2" thru_hole circle
			(at 1.27 -3.348736 180)
			(size 2.159 2.159)
			(drill 1.7018)
			(layers "*.Cu" "*.Mask")
			(remove_unused_layers no)
			(net "TDR_SE_50_OHM_BOT")
			(clearance 0.0254)
			(thermal_gap 0.0254)
		)
		(pad "3" thru_hole circle
			(at -1.27 -3.348736 180)
			(size 2.159 2.159)
			(drill 1.7018)
			(layers "*.Cu" "*.Mask")
			(remove_unused_layers no)
			(net "TDR_SE_50_OHM_BOT")
			(clearance 0.0254)
			(thermal_gap 0.0254)
		)
	)
)
